# T6G (Grand Teton) — schematic netlist excerpt (pin names and nets, part order shuffled) for the footprints in the layout excerpt that follows; sources: Cadence DE-HDL packaged netlist, KiCad conversion of 04192023_DAF0TMB3IC0_F0TG_MB_C_brd_V02_OCP.brd

R4198  Q_RES  1K 1% EMPTY  pkg 0402LF  page 235 : A = P3V3_AUX ; B = U270_0_ADD1
R652  Q_RES  1K 1% CHIP  pkg 0402LF  page 362 : A = P3V3_AUX ; B = P0V9_RETIMER_CPU0_CFP

(kicad_pcb
	(version 20260206)
	(generator "pcbnew")
	(generator_version "10.0")
	(general
		(thickness 1.6)
		(legacy_teardrops no)
	)
	(paper "A4")
	(title_block
		(title "04192023_DAF0TMB3IC0_F0TG_MB_C_brd_V02_OCP.brd")
		(comment 1 "Grand Teton / footprints 4911-4912 of 8354")
	)
	(layers
		(0 "F.Cu" signal "TOP")
		(4 "In1.Cu" signal "GND")
		(6 "In2.Cu" signal "IN1")
		(8 "In3.Cu" signal "GND1")
		(10 "In4.Cu" signal "IN2")
		(12 "In5.Cu" signal "GND2")
		(14 "In6.Cu" signal "IN3")
		(16 "In7.Cu" signal "GND3")
		(18 "In8.Cu" signal "VCC")
		(20 "In9.Cu" signal "VCC1")
		(22 "In10.Cu" signal "GND4")
		(24 "In11.Cu" signal "IN4")
		(26 "In12.Cu" signal "GND5")
		(28 "In13.Cu" signal "IN5")
		(30 "In14.Cu" signal "GND6")
		(32 "In15.Cu" signal "IN6")
		(34 "In16.Cu" signal "GND7")
		(2 "B.Cu" signal "BOTTOM")
		(9 "F.Adhes" user "F.Adhesive")
		(11 "B.Adhes" user "B.Adhesive")
		(13 "F.Paste" user "Package Geometry/Pastemask Top")
		(15 "B.Paste" user "Package Geometry/Pastemask Bottom")
		(5 "F.SilkS" user "Ref Des/Silkscreen Top")
		(7 "B.SilkS" user "Ref Des/Silkscreen Bottom")
		(1 "F.Mask" user "Board Geometry/Soldermask Top")
		(3 "B.Mask" user "Board Geometry/Soldermask Bottom")
		(17 "Dwgs.User" user "User.Drawings")
		(19 "Cmts.User" user "User.Comments")
		(21 "Eco1.User" user "User.Eco1")
		(23 "Eco2.User" user "User.Eco2")
		(25 "Edge.Cuts" user "Board Geometry/Outline")
		(27 "Margin" user)
		(31 "F.CrtYd" user "Package Geometry/Place Bound Top")
		(29 "B.CrtYd" user "Package Geometry/Place Bound Bottom")
		(35 "F.Fab" user "Ref Des/Assembly Top")
		(33 "B.Fab" user "Ref Des/Assembly Bottom")
	)
	(footprint ""
		(layer "F.Cu")
		(at 368.06378 -427.411388 -90)
		(property "Reference" "R4198"
			(at 0 0 270)
			(layer "F.SilkS")
			(hide yes)
			(effects
				(font
					(size 1.27 1.27)
				)
			)
		)
		(property "Value" ""
			(at 0 0 270)
			(layer "F.Fab")
			(effects
				(font
					(size 1.27 1.27)
				)
			)
		)
		(duplicate_pad_numbers_are_jumpers no)
		(fp_line
			(start -0.7874 0.4064)
			(end -0.7874 -0.4064)
			(stroke
				(width 0.1524)
				(type default)
			)
			(layer "F.SilkS")
		)
		(fp_line
			(start 0.7874 0.4064)
			(end -0.7874 0.4064)
			(stroke
				(width 0.1524)
				(type default)
			)
			(layer "F.SilkS")
		)
		(fp_line
			(start -0.7874 -0.4064)
			(end 0.7874 -0.4064)
			(stroke
				(width 0.1524)
				(type default)
			)
			(layer "F.SilkS")
		)
		(fp_line
			(start 0.7874 -0.4064)
			(end 0.7874 0.4064)
			(stroke
				(width 0.1524)
				(type default)
			)
			(layer "F.SilkS")
		)
		(fp_line
			(start -0.67945 0.3048)
			(end -0.67945 -0.305054)
			(stroke
				(width 0.1)
				(type default)
			)
			(layer "F.Fab")
		)
		(fp_line
			(start -0.12065 0.3048)
			(end -0.67945 0.3048)
			(stroke
				(width 0.1)
				(type default)
			)
			(layer "F.Fab")
		)
		(fp_line
			(start 0.120396 0.3048)
			(end 0.120396 0.2794)
			(stroke
				(width 0.1)
				(type default)
			)
			(layer "F.Fab")
		)
		(fp_line
			(start 0.67945 0.3048)
			(end 0.120396 0.3048)
			(stroke
				(width 0.1)
				(type default)
			)
			(layer "F.Fab")
		)
		(fp_line
			(start -0.12065 0.2794)
			(end -0.12065 0.3048)
			(stroke
				(width 0.1)
				(type default)
			)
			(layer "F.Fab")
		)
		(fp_line
			(start 0.120396 0.2794)
			(end -0.12065 0.2794)
			(stroke
				(width 0.1)
				(type default)
			)
			(layer "F.Fab")
		)
		(fp_line
			(start -0.12065 -0.2794)
			(end 0.12065 -0.2794)
			(stroke
				(width 0.1)
				(type default)
			)
			(layer "F.Fab")
		)
		(fp_line
			(start 0.12065 -0.2794)
			(end 0.12065 -0.3048)
			(stroke
				(width 0.1)
				(type default)
			)
			(layer "F.Fab")
		)
		(fp_line
			(start 0.12065 -0.3048)
			(end 0.67945 -0.3048)
			(stroke
				(width 0.1)
				(type default)
			)
			(layer "F.Fab")
		)
		(fp_line
			(start 0.67945 -0.3048)
			(end 0.67945 0.3048)
			(stroke
				(width 0.1)
				(type default)
			)
			(layer "F.Fab")
		)
		(fp_line
			(start -0.67945 -0.305054)
			(end -0.12065 -0.305054)
			(stroke
				(width 0.1)
				(type default)
			)
			(layer "F.Fab")
		)
		(fp_line
			(start -0.12065 -0.305054)
			(end -0.12065 -0.2794)
			(stroke
				(width 0.1)
				(type default)
			)
			(layer "F.Fab")
		)
		(pad "1" smd circle
			(at -0.40005 0 270)
			(size 0 0)
			(layers "F.Cu" "F.Mask" "F.Paste")
			(net "P3V3_AUX")
		)
		(pad "2" smd circle
			(at 0.40005 0 270)
			(size 0 0)
			(layers "F.Cu" "F.Mask" "F.Paste")
			(net "U270_0_ADD1")
		)
	)
	(footprint ""
		(layer "F.Cu")
		(at 449.443602 -420.99611 180)
		(property "Reference" "R652"
			(at 0 0 180)
			(layer "F.SilkS")
			(hide yes)
			(effects
				(font
					(size 1.27 1.27)
				)
			)
		)
		(property "Value" ""
			(at 0 0 180)
			(layer "F.Fab")
			(effects
				(font
					(size 1.27 1.27)
				)
			)
		)
		(duplicate_pad_numbers_are_jumpers no)
		(fp_line
			(start 0.7874 0.4064)
			(end -0.7874 0.4064)
			(stroke
				(width 0.1524)
				(type default)
			)
			(layer "F.SilkS")
		)
		(fp_line
			(start 0.7874 -0.4064)
			(end 0.7874 0.4064)
			(stroke
				(width 0.1524)
				(type default)
			)
			(layer "F.SilkS")
		)
		(fp_line
			(start -0.7874 0.4064)
			(end -0.7874 -0.4064)
			(stroke
				(width 0.1524)
				(type default)
			)
			(layer "F.SilkS")
		)
		(fp_line
			(start -0.7874 -0.4064)
			(end 0.7874 -0.4064)
			(stroke
				(width 0.1524)
				(type default)
			)
			(layer "F.SilkS")
		)
		(fp_line
			(start 0.67945 0.3048)
			(end 0.120396 0.3048)
			(stroke
				(width 0.1)
				(type default)
			)
			(layer "F.Fab")
		)
		(fp_line
			(start 0.67945 -0.3048)
			(end 0.67945 0.3048)
			(stroke
				(width 0.1)
				(type default)
			)
			(layer "F.Fab")
		)
		(fp_line
			(start 0.12065 -0.2794)
			(end 0.12065 -0.3048)
			(stroke
				(width 0.1)
				(type default)
			)
			(layer "F.Fab")
		)
		(fp_line
			(start 0.12065 -0.3048)
			(end 0.67945 -0.3048)
			(stroke
				(width 0.1)
				(type default)
			)
			(layer "F.Fab")
		)
		(fp_line
			(start 0.120396 0.3048)
			(end 0.120396 0.2794)
			(stroke
				(width 0.1)
				(type default)
			)
			(layer "F.Fab")
		)
		(fp_line
			(start 0.120396 0.2794)
			(end -0.12065 0.2794)
			(stroke
				(width 0.1)
				(type default)
			)
			(layer "F.Fab")
		)
		(fp_line
			(start -0.12065 0.3048)
			(end -0.67945 0.3048)
			(stroke
				(width 0.1)
				(type default)
			)
			(layer "F.Fab")
		)
		(fp_line
			(start -0.12065 0.2794)
			(end -0.12065 0.3048)
			(stroke
				(width 0.1)
				(type default)
			)
			(layer "F.Fab")
		)
		(fp_line
			(start -0.12065 -0.2794)
			(end 0.12065 -0.2794)
			(stroke
				(width 0.1)
				(type default)
			)
			(layer "F.Fab")
		)
		(fp_line
			(start -0.12065 -0.305054)
			(end -0.12065 -0.2794)
			(stroke
				(width 0.1)
				(type default)
			)
			(layer "F.Fab")
		)
		(fp_line
			(start -0.67945 0.3048)
			(end -0.67945 -0.305054)
			(stroke
				(width 0.1)
				(type default)
			)
			(layer "F.Fab")
		)
		(fp_line
			(start -0.67945 -0.305054)
			(end -0.12065 -0.305054)
			(stroke
				(width 0.1)
				(type default)
			)
			(layer "F.Fab")
		)
		(pad "1" smd circle
			(at -0.40005 0 180)
			(size 0 0)
			(layers "F.Cu" "F.Mask" "F.Paste")
			(net "P3V3_AUX")
		)
		(pad "2" smd circle
			(at 0.40005 0 180)
			(size 0 0)
			(layers "F.Cu" "F.Mask" "F.Paste")
			(net "P0V9_RETIMER_CPU0_CFP")
		)
	)
)
